# BASEBOARD_FAB2 (Tioga Pass) — schematic netlist excerpt (pin names and nets, part order shuffled) for the footprints in the layout excerpt that follows; sources: Cadence DE-HDL packaged netlist, KiCad conversion of Wiwynn_Tioga_Pass_MB.brd

C8D3  CAP  470PF 50V 10% EMPTY  pkg 0402LF  page 170 : A = IRQ_SML1_PMBUS_ALERT_N ; B = GND
C12W2  CAP  47.0PF 50V 5% COG  pkg 0402LF  page 197 : A = VR_PVDDQ_DEF_AIINSEN ; B = VR_PVDDQ_DEF_VINSEN
L4E1  IND-120NH-30-GP  pkg DISCRET-GB2  page 202 : S = VR_PVCCIN_CPU0_PHASE1 ; F = PVCCIN_CPU0

(kicad_pcb
	(version 20260206)
	(generator "pcbnew")
	(generator_version "10.0")
	(general
		(thickness 1.6)
		(legacy_teardrops no)
	)
	(paper "A4")
	(title_block
		(title "Wiwynn_Tioga_Pass_MB.brd")
		(comment 1 "Tioga Pass / footprints 337-339 of 4770")
	)
	(layers
		(0 "F.Cu" signal "TOP")
		(4 "In1.Cu" signal "L2GND")
		(6 "In2.Cu" signal "L3")
		(8 "In3.Cu" signal "L4GND")
		(10 "In4.Cu" signal "L5")
		(12 "In5.Cu" signal "L6GND")
		(14 "In6.Cu" signal "L7VCC")
		(16 "In7.Cu" signal "L8VCC")
		(18 "In8.Cu" signal "L9GND")
		(20 "In9.Cu" signal "L10")
		(22 "In10.Cu" signal "L11GND")
		(24 "In11.Cu" signal "L12")
		(26 "In12.Cu" signal "L13GND")
		(2 "B.Cu" signal "BOTTOM")
		(9 "F.Adhes" user "F.Adhesive")
		(11 "B.Adhes" user "B.Adhesive")
		(13 "F.Paste" user "Package Geometry/Pastemask Top")
		(15 "B.Paste" user "Package Geometry/Pastemask Bottom")
		(5 "F.SilkS" user "Ref Des/Silkscreen Top")
		(7 "B.SilkS" user "Ref Des/Silkscreen Bottom")
		(1 "F.Mask" user "Board Geometry/Soldermask Top")
		(3 "B.Mask" user "Board Geometry/Soldermask Bottom")
		(17 "Dwgs.User" user "User.Drawings")
		(19 "Cmts.User" user "User.Comments")
		(21 "Eco1.User" user "User.Eco1")
		(23 "Eco2.User" user "User.Eco2")
		(25 "Edge.Cuts" user "Board Geometry/Outline")
		(27 "Margin" user)
		(31 "F.CrtYd" user "Package Geometry/Place Bound Top")
		(29 "B.CrtYd" user "Package Geometry/Place Bound Bottom")
		(35 "F.Fab" user "Ref Des/Assembly Top")
		(33 "B.Fab" user "Ref Des/Assembly Bottom")
	)
	(footprint ""
		(layer "F.Cu")
		(at 417.703 -83.439 -90)
		(property "Reference" "C8D3"
			(at 0 0 270)
			(layer "F.SilkS")
			(hide yes)
			(effects
				(font
					(size 1.27 1.27)
				)
			)
		)
		(property "Value" ""
			(at 0 0 270)
			(layer "F.Fab")
			(effects
				(font
					(size 1.27 1.27)
				)
			)
		)
		(duplicate_pad_numbers_are_jumpers no)
		(fp_poly
			(pts
				(xy 0.3048 -0.1016) (xy 0.3048 0.9906) (xy -0.3048 0.9906) (xy -0.3048 -0.1016)
			)
			(stroke
				(width 0)
				(type default)
			)
			(fill no)
			(layer "F.CrtYd")
		)
		(fp_line
			(start -0.3048 0.9906)
			(end 0.3048 0.9906)
			(stroke
				(width 0.1)
				(type default)
			)
			(layer "F.Fab")
		)
		(fp_line
			(start 0.3048 0.9906)
			(end 0.3048 -0.1016)
			(stroke
				(width 0.1)
				(type default)
			)
			(layer "F.Fab")
		)
		(fp_line
			(start -0.3048 -0.1016)
			(end -0.3048 0.9906)
			(stroke
				(width 0.1)
				(type default)
			)
			(layer "F.Fab")
		)
		(fp_line
			(start 0.3048 -0.1016)
			(end -0.3048 -0.1016)
			(stroke
				(width 0.1)
				(type default)
			)
			(layer "F.Fab")
		)
		(pad "1" smd rect
			(at 0 0 270)
			(size 0.508 0.508)
			(layers "F.Cu" "F.Mask" "F.Paste")
			(net "IRQ_SML1_PMBUS_ALERT_N")
		)
		(pad "2" smd rect
			(at 0 0.889 270)
			(size 0.508 0.508)
			(layers "F.Cu" "F.Mask" "F.Paste")
			(net "GND")
		)
		(zone
			(layer "F.Cu")
			(hatch none 0.5)
			(connect_pads
				(clearance 0)
			)
			(min_thickness 0.25)
			(keepout
				(tracks not_allowed)
				(vias allowed)
				(pads allowed)
				(copperpour not_allowed)
				(footprints allowed)
			)
			(placement
				(enabled no)
				(sheetname "")
			)
			(fill
				(thermal_gap 0.5)
				(thermal_bridge_width 0.5)
				(island_removal_mode 0)
			)
			(polygon
				(pts
					(xy 417.068 -83.693) (xy 417.068 -83.185) (xy 417.449 -83.185) (xy 417.449 -83.693)
				)
			)
		)
		(zone
			(layer "F.Cu")
			(hatch none 0.5)
			(connect_pads
				(clearance 0)
			)
			(min_thickness 0.25)
			(keepout
				(tracks allowed)
				(vias not_allowed)
				(pads allowed)
				(copperpour not_allowed)
				(footprints allowed)
			)
			(placement
				(enabled no)
				(sheetname "")
			)
			(fill
				(thermal_gap 0.5)
				(thermal_bridge_width 0.5)
				(island_removal_mode 0)
			)
			(polygon
				(pts
					(xy 417.449 -83.693) (xy 417.449 -83.185) (xy 417.068 -83.185) (xy 417.068 -83.693)
				)
			)
		)
	)
	(footprint ""
		(layer "F.Cu")
		(at 205.036928 -57.031382)
		(property "Reference" "L4E1"
			(at 3.378708 -4.251706 0)
			(unlocked yes)
			(layer "F.SilkS")
			(effects
				(font
					(size 0.4064 0.254)
					(thickness 0.1524)
				)
			)
		)
		(property "Value" ""
			(at 0 0 0)
			(layer "F.Fab")
			(effects
				(font
					(size 1.27 1.27)
				)
			)
		)
		(duplicate_pad_numbers_are_jumpers no)
		(fp_line
			(start -1.1303 -3.199892)
			(end 8.3693 -3.199892)
			(stroke
				(width 0.1524)
				(type default)
			)
			(layer "F.SilkS")
		)
		(fp_line
			(start -1.1303 -1.6637)
			(end -1.1303 -3.199892)
			(stroke
				(width 0.1524)
				(type default)
			)
			(layer "F.SilkS")
		)
		(fp_line
			(start -1.1303 3.199892)
			(end -1.1303 1.6637)
			(stroke
				(width 0.1524)
				(type default)
			)
			(layer "F.SilkS")
		)
		(fp_line
			(start 8.3693 -3.199892)
			(end 8.3693 -1.6637)
			(stroke
				(width 0.1524)
				(type default)
			)
			(layer "F.SilkS")
		)
		(fp_line
			(start 8.3693 1.6637)
			(end 8.3693 3.199892)
			(stroke
				(width 0.1524)
				(type default)
			)
			(layer "F.SilkS")
		)
		(fp_line
			(start 8.3693 3.199892)
			(end -1.1303 3.199892)
			(stroke
				(width 0.1524)
				(type default)
			)
			(layer "F.SilkS")
		)
		(fp_rect
			(start -1.1303 3.199892)
			(end 8.3693 -3.199892)
			(stroke
				(width 0)
				(type default)
			)
			(fill no)
			(layer "F.CrtYd")
		)
		(fp_line
			(start -1.1303 -3.199892)
			(end 8.3693 -3.199892)
			(stroke
				(width 0.1)
				(type default)
			)
			(layer "F.Fab")
		)
		(fp_line
			(start -1.1303 3.199892)
			(end -1.1303 -3.199892)
			(stroke
				(width 0.1)
				(type default)
			)
			(layer "F.Fab")
		)
		(fp_line
			(start 8.3693 -3.199892)
			(end 8.3693 3.199892)
			(stroke
				(width 0.1)
				(type default)
			)
			(layer "F.Fab")
		)
		(fp_line
			(start 8.3693 3.199892)
			(end -1.1303 3.199892)
			(stroke
				(width 0.1)
				(type default)
			)
			(layer "F.Fab")
		)
		(pad "1" smd rect
			(at 0 0)
			(size 3.683 2.667)
			(layers "F.Cu" "F.Mask" "F.Paste")
			(net "VR_PVCCIN_CPU0_PHASE1")
		)
		(pad "2" smd rect
			(at 7.239 0)
			(size 3.683 2.667)
			(layers "F.Cu" "F.Mask" "F.Paste")
			(net "PVCCIN_CPU0")
		)
	)
	(footprint ""
		(layer "F.Cu")
		(at 355.149404 -137.150348 180)
		(property "Reference" "C12W2"
			(at -0.8382 -0.67818 180)
			(unlocked yes)
			(layer "F.SilkS")
			(effects
				(font
					(size 0.4064 0.254)
					(thickness 0.1524)
				)
				(justify left)
			)
		)
		(property "Value" ""
			(at 0 0 180)
			(layer "F.Fab")
			(effects
				(font
					(size 1.27 1.27)
				)
			)
		)
		(duplicate_pad_numbers_are_jumpers no)
		(fp_poly
			(pts
				(xy 0.3048 -0.1016) (xy 0.3048 0.9906) (xy -0.3048 0.9906) (xy -0.3048 -0.1016)
			)
			(stroke
				(width 0)
				(type default)
			)
			(fill no)
			(layer "F.CrtYd")
		)
		(fp_line
			(start 0.3048 0.9906)
			(end 0.3048 -0.1016)
			(stroke
				(width 0.1)
				(type default)
			)
			(layer "F.Fab")
		)
		(fp_line
			(start 0.3048 -0.1016)
			(end -0.3048 -0.1016)
			(stroke
				(width 0.1)
				(type default)
			)
			(layer "F.Fab")
		)
		(fp_line
			(start -0.3048 0.9906)
			(end 0.3048 0.9906)
			(stroke
				(width 0.1)
				(type default)
			)
			(layer "F.Fab")
		)
		(fp_line
			(start -0.3048 -0.1016)
			(end -0.3048 0.9906)
			(stroke
				(width 0.1)
				(type default)
			)
			(layer "F.Fab")
		)
		(pad "1" smd rect
			(at 0 0 180)
			(size 0.508 0.508)
			(layers "F.Cu" "F.Mask" "F.Paste")
			(net "VR_PVDDQ_DEF_AIINSEN")
		)
		(pad "2" smd rect
			(at 0 0.889 180)
			(size 0.508 0.508)
			(layers "F.Cu" "F.Mask" "F.Paste")
			(net "VR_PVDDQ_DEF_VINSEN")
		)
		(zone
			(layer "F.Cu")
			(hatch none 0.5)
			(connect_pads
				(clearance 0)
			)
			(min_thickness 0.25)
			(keepout
				(tracks not_allowed)
				(vias allowed)
				(pads allowed)
				(copperpour not_allowed)
				(footprints allowed)
			)
			(placement
				(enabled no)
				(sheetname "")
			)
			(fill
				(thermal_gap 0.5)
				(thermal_bridge_width 0.5)
				(island_removal_mode 0)
			)
			(polygon
				(pts
					(xy 355.403404 -137.785348) (xy 354.895404 -137.785348) (xy 354.895404 -137.404348) (xy 355.403404 -137.404348)
				)
			)
		)
		(zone
			(layer "F.Cu")
			(hatch none 0.5)
			(connect_pads
				(clearance 0)
			)
			(min_thickness 0.25)
			(keepout
				(tracks allowed)
				(vias not_allowed)
				(pads allowed)
				(copperpour not_allowed)
				(footprints allowed)
			)
			(placement
				(enabled no)
				(sheetname "")
			)
			(fill
				(thermal_gap 0.5)
				(thermal_bridge_width 0.5)
				(island_removal_mode 0)
			)
			(polygon
				(pts
					(xy 355.403404 -137.404348) (xy 354.895404 -137.404348) (xy 354.895404 -137.785348) (xy 355.403404 -137.785348)
				)
			)
		)
	)
)
